FILE_TYPE = MULTI_PHYS_TABLE;

PART '74LVC1G08GW'

{========================================================================================}
:VALUE         | PACK_TYPE | MATERIAL | PART_NUMBER         = STANDARD         | LIFECYCLE        | ENVCOMP | PART_NUMBER      | JEDEC_TYPE | CLASS | DESCRIPTION                   | HEIGHT   | COMPONENT_TYPE | LEAD_LENGTH | LPID | DAY;
{========================================================================================}
 '74LVC1G08GW' | 'SM'      | 'IC'     | 'ALVC1G08009'(!) = 'End of Design'  | 'Comp-Approve'   | 'YES'   | 'ALVC1G08009' |'SC70-5'| 'IC'  | 'IC(5P) 74LVC1G08GW (SC70-5)' | '.044IN' | 'SMALLSMT'     | ''          | ''  | '20100711'
 '74LVC1G08GW' | 'SM'      | 'EMPTY'  | 'ALVC1G08009'(!) = 'End of Design'  | 'Comp-Approve'   | 'YES'   | 'ALVC1G08009' |'SC70-5'| 'IO'  | 'IC(5P) 74LVC1G08GW (SC70-5)' | '.044IN' | 'SMALLSMT'     | ''          | ''  | '20100711'

END_PART

END.

